FILE_TYPE = CONNECTIVITY;
{Allegro Design Entry HDL 16.6-p007 (v16-6-112F) 10/10/2012}
"PAGE_NUMBER" = 232;
0"NC";
1"PVPP_DEF\g";
2"GND\g";
3"GND\g";
4"AGND_PVPP_DEF\g";
5"PVPP_DEF\g";
6"GND\g";
7"P12V_STBY\g";
8"GND\g";
9"P3V3_STBY\g";
10"GND\g";
11"GND\g";
12"GND\g";
13"GND\g";
14"GND\g";
15"GND\g";
16"AGND_PVPP_DEF\g";
17"AGND_PVPP_DEF\g";
18"AGND_PVPP_DEF\g";
19"AGND_PVPP_DEF\g";
20"AGND_PVPP_DEF\g";
21"AGND_PVPP_DEF\g";
22"GND\g";
23"GND\g";
24"GND\g";
25"GND\g";
26"GND\g";
27"AGND_PVPP_DEF\g";
28"GND\g";
29"GND\g";
30"FM_PVPP_PVDDQ_CPU0_EN_DEF";
31"VR_FB_PVPP_DEF";
32"PWRGD_PVPP_DEF_R";
33"VR_PVPP_DEF_ISET";
34"VR_FET_SW_P12V_STBY_PVPP_DEF";
35"VR_VB_PVPP_DEF";
36"VR_PVPP_DEF_SNUB";
37"VR_COMP_PVPP_DEF";
38"PWRGD_PVPP_DEF";
39"VR_COMP_PVPP_DEF_3";
40"VR_PVPP_DEF_PHASE";
41"VSENSE_PVPP_DEF";
42"VR_COMP_RC_PVPP_DEF";
43"VR_PVPP_DEF_BOOT_R";
44"VR_PVPP_DEF_BOOT";
45"FM_PVPP_CPU0_EN";
46"VR_PVPP_DEF_SS";
%"CAP"
"1","(-8600,875)","0","mstr_discrete","I102";
;
VOLTAGE"4V"
TOLERANCE"20%"
MATERIAL"X6S"
PACK_TYPE"0603LF"
VALUE"10UF"
LOCATION"C4L2"
PART_NUMBER"E15431-001"
GROUP"PWR_MLCC_CAP"
CDS_LIB"mstr_discrete"
CDS_LOCATION"C4L2"
ROOM"PVPP_KLM_VR"
$SEC"1"
CDS_SEC"1"
BOM_COST"MEM_VRD_PVPP_AB";
"A"
$PN"1"1;
"B"
$PN"2"2;
%"PVPP_DEF"
"1","(-8600,1150)","0","mstr_symbols","I103";
;
VOLTAGE"2.5V"
CDS_LIB"mstr_symbols"
BOM_COST"MEM_VRD_PVPP_AB"
ROOM"PVPP_KLM_VR"
BODY_TYPE"PLUMBING"
HDL_POWER"PVPP_DEF";
"G\NAC"1;
%"CAP"
"1","(-8325,875)","0","mstr_discrete","I104";
;
VALUE"10UF"
LOCATION"C6A3"
VOLTAGE"4V"
TOLERANCE"20%"
MATERIAL"X6S"
PART_NUMBER"E15431-001"
PACK_TYPE"0603LF"
GROUP"PWR_MLCC_CAP"
CDS_LIB"mstr_discrete"
CDS_LOCATION"C6A3"
BOM_COST"MEM_VRD_PVPP_AB"
CDS_SEC"1"
$SEC"1"
ROOM"PVPP_KLM_VR";
"A"
$PN"1"1;
"B"
$PN"2"2;
%"CAP"
"1","(-8050,875)","0","mstr_discrete","I105";
;
VALUE"10UF"
VOLTAGE"4V"
MATERIAL"X6S"
LOCATION"C6A2"
TOLERANCE"20%"
PACK_TYPE"0603LF"
PART_NUMBER"E15431-001"
GROUP"PWR_MLCC_CAP"
CDS_LIB"mstr_discrete"
CDS_LOCATION"C6A2"
BOM_COST"MEM_VRD_PVPP_AB"
CDS_SEC"1"
$SEC"1"
ROOM"PVPP_KLM_VR";
"A"
$PN"1"1;
"B"
$PN"2"2;
%"CAP"
"1","(-7775,875)","0","mstr_discrete","I106";
;
MATERIAL"X6S"
TOLERANCE"20%"
LOCATION"C4L3"
VALUE"10UF"
VOLTAGE"4V"
PACK_TYPE"0603LF"
PART_NUMBER"E15431-001"
GROUP"PWR_MLCC_CAP"
CDS_LIB"mstr_discrete"
CDS_LOCATION"C4L3"
ROOM"PVPP_KLM_VR"
BOM_COST"MEM_VRD_PVPP_AB"
CDS_SEC"1"
$SEC"1";
"A"
$PN"1"1;
"B"
$PN"2"2;
%"CAP"
"1","(-7500,875)","0","mstr_discrete","I108";
;
MATERIAL"X6S"
VALUE"10UF"
PART_NUMBER"E15431-001"
LOCATION"C4L4"
PACK_TYPE"0603LF"
TOLERANCE"20%"
VOLTAGE"4V"
GROUP"PWR_MLCC_CAP"
ROOM"PVPP_KLM_VR"
$SEC"1"
CDS_SEC"1"
BOM_COST"MEM_VRD_PVPP_AB"
CDS_LOCATION"C4L4"
CDS_LIB"mstr_discrete";
"A"
$PN"1"1;
"B"
$PN"2"2;
%"CAP"
"1","(-7200,875)","0","mstr_discrete","I109";
;
PART_NUMBER"E15431-001"
TOLERANCE"20%"
MATERIAL"X6S"
VALUE"10UF"
LOCATION"C6A7"
VOLTAGE"4V"
PACK_TYPE"0603LF"
GROUP"PWR_MLCC_CAP"
BOM_COST"MEM_VRD_PVPP_AB"
CDS_SEC"1"
$SEC"1"
ROOM"PVPP_KLM_VR"
CDS_LOCATION"C6A7"
CDS_LIB"mstr_discrete";
"A"
$PN"1"1;
"B"
$PN"2"2;
%"CAP"
"1","(-6925,875)","0","mstr_discrete","I110";
;
VOLTAGE"4V"
LOCATION"C6A6"
MATERIAL"X6S"
TOLERANCE"20%"
VALUE"10UF"
PART_NUMBER"E15431-001"
PACK_TYPE"0603LF"
GROUP"PWR_MLCC_CAP"
BOM_COST"MEM_VRD_PVPP_AB"
CDS_SEC"1"
$SEC"1"
ROOM"PVPP_KLM_VR"
CDS_LOCATION"C6A6"
CDS_LIB"mstr_discrete";
"A"
$PN"1"1;
"B"
$PN"2"2;
%"CAP"
"1","(-6625,875)","0","mstr_discrete","I111";
;
VOLTAGE"4V"
TOLERANCE"20%"
VALUE"10UF"
LOCATION"C4M3"
PART_NUMBER"E15431-001"
MATERIAL"X6S"
PACK_TYPE"0603LF"
GROUP"PWR_MLCC_CAP"
ROOM"PVPP_KLM_VR"
$SEC"1"
CDS_SEC"1"
BOM_COST"MEM_VRD_PVPP_AB"
CDS_LOCATION"C4M3"
CDS_LIB"mstr_discrete";
"A"
$PN"1"1;
"B"
$PN"2"2;
%"CAP"
"1","(-6325,875)","0","mstr_discrete","I125";
;
VOLTAGE"4V"
MATERIAL"X6S"
PACK_TYPE"0603LF"
VALUE"10UF"
TOLERANCE"20%"
LOCATION"C4M4"
PART_NUMBER"E15431-001"
GROUP"PWR_MLCC_CAP"
ROOM"PVPP_KLM_VR"
$SEC"1"
CDS_SEC"1"
BOM_COST"MEM_VRD_PVPP_AB"
CDS_LIB"mstr_discrete"
CDS_LOCATION"C4M4";
"A"
$PN"1"1;
"B"
$PN"2"2;
%"CAP"
"1","(-6050,875)","0","mstr_discrete","I126";
;
PACK_TYPE"0603LF"
VALUE"10UF"
LOCATION"C6B2"
VOLTAGE"4V"
PART_NUMBER"E15431-001"
MATERIAL"X6S"
TOLERANCE"20%"
GROUP"PWR_MLCC_CAP"
CDS_LIB"mstr_discrete"
CDS_LOCATION"C6B2"
ROOM"PVPP_KLM_VR"
BOM_COST"MEM_VRD_PVPP_AB"
$SEC"1"
CDS_SEC"1";
"A"
$PN"1"1;
"B"
$PN"2"2;
%"GND"
"1","(-8600,475)","0","mstr_symbols","I127";
;
VOLTAGE"0"
CDS_LIB"mstr_symbols"
SIZE"1B"
BOM_COST"MEM_VRD_PVPP_AB"
ROOM"PVPP_KLM_VR"
BODY_TYPE"PLUMBING"
HDL_POWER"GND";
"A\NAC"2;
%"CAP"
"1","(-5775,875)","0","mstr_discrete","I128";
;
MATERIAL"X6S"
PACK_TYPE"0603LF"
LOCATION"C6B1"
PART_NUMBER"E15431-001"
VALUE"10UF"
VOLTAGE"4V"
TOLERANCE"20%"
GROUP"PWR_MLCC_CAP"
CDS_LIB"mstr_discrete"
CDS_LOCATION"C6B1"
ROOM"PVPP_KLM_VR"
BOM_COST"MEM_VRD_PVPP_AB"
$SEC"1"
CDS_SEC"1";
"A"
$PN"1"1;
"B"
$PN"2"2;
%"CAP"
"1","(-5500,875)","0","mstr_discrete","I129";
;
CDS_SEC"1"
VOLTAGE"4V"
PACK_TYPE"0603LF"
VALUE"10UF"
TOLERANCE"20%"
PART_NUMBER"E15431-001"
MATERIAL"X6S"
LOCATION"C4L1"
GROUP"PWR_MLCC_CAP"
CDS_LOCATION"C4L1"
CDS_LIB"mstr_discrete"
ROOM"PVPP_KLM_VR"
SEC"1"
SEC_TYPE"0603LF"
BOM_COST"MEM_VRD_PVPP_AB";
"A"
$PN"1"1;
"B"
$PN"2"2;
%"GND"
"1","(-1875,675)","0","mstr_symbols","I149";
;
SIZE"1B"
CDS_LIB"mstr_symbols"
VOLTAGE"0"
ROOM"PVPP_KLM_VR"
BOM_COST"PVPP_KLM_VR"
BODY_TYPE"PLUMBING"
HDL_POWER"GND";
"A\NAC"3;
%"RES"
"1","(-1575,775)","0","mstr_discrete","I150";
;
CDS_LOCATION"R7B20"
PACK_TYPE"0402"
MATERIAL"CHIP"
WATTAGE"1/16W"
VALUE"0.0"
LOCATION"R7B20"
TOLERANCE"5%"
PART_NUMBER"G21497-005"
ROOM"PVPP_KLM_VR"
$SEC"1"
CDS_SEC"1"
CDS_LIB"mstr_discrete";
"B"
$PN"2"4;
"A"
$PN"1"3;
%"AGND_SCSI"
"1","(-1325,675)","0","mstr_symbols","I151";
;
HDL_POWER"AGND_PVPP_DEF"
ROOM"PVPP_KLM_VR"
CDS_LIB"mstr_symbols"
BOM_COST"PVPP_KLM_VR"
VOLTAGE"0.0V"
BODY_TYPE"PLUMBING";
"A"4;
%"PVPP_DEF"
"1","(-1150,3975)","0","mstr_symbols","I167";
;
BOM_COST"PVPP_KLM_VR"
ROOM"PVPP_KLM_VR"
CDS_LIB"mstr_symbols"
VOLTAGE"2.5V"
BODY_TYPE"PLUMBING"
HDL_POWER"PVPP_DEF";
"G\NAC"5;
%"CAP"
"1","(-6825,2500)","2","mstr_discrete","I185";
;
PACK_TYPE"0402LF"
PART_NUMBER"A36096-046"
MATERIAL"EMPTY"
TOLERANCE"10%"
VOLTAGE"50V"
LOCATION"C7B9"
VALUE"1000PF"
FIN"VR_1P2"
REUSE_ID"1"
CDS_SEC"1"
$SEC"1"
CDS_LOCATION"C7B9"
CDS_LIB"mstr_discrete"
BOM_COST"PVPP_KLM_VR"
ROOM"PVPP_KLM_VR";
"A"
$PN"1"45;
"B"
$PN"2"20;
%"CAP"
"1","(-5425,2175)","0","mstr_discrete","I197";
;
CDS_SEC"1"
TOLERANCE"10%"
VOLTAGE"16V"
LOCATION"C7B11"
VALUE"0.027UF"
PACK_TYPE"0402"
PART_NUMBER"A36096-129"
MATERIAL"X7R"
SEC_TYPE"0402"
REUSE_ID"26"
BOM_COST"PVPP_KLM_VR"
SEC"1"
CDS_LOCATION"C7B11"
ROOM"PVPP_KLM_VR"
CDS_LIB"mstr_discrete";
"A"
$PN"1"46;
"B"
$PN"2"17;
%"GND"
"1","(-5425,3900)","0","mstr_symbols","I198";
;
CDS_LIB"mstr_symbols"
VOLTAGE"0"
SIZE"1B"
ROOM"PVPP_KLM_VR"
BOM_COST"PVPP_KLM_VR"
BODY_TYPE"PLUMBING"
HDL_POWER"GND";
"A\NAC"6;
%"P12V_STBY"
"1","(-8175,4500)","0","mstr_symbols","I199";
;
SIZE"1B"
VOLTAGE"12.0V"
CDS_LIB"mstr_symbols"
BODY_TYPE"PLUMBING"
HDL_POWER"P12V_STBY";
"G\NAC"7;
%"FERRITE"
"1","(-7950,4300)","0","mstr_discrete","I200";
;
CDS_SEC"1"
PACK_TYPE"SM"
PART_NUMBER"656554-051"
MATERIAL"FB"
VALUE"22"
LOCATION"FB7B1"
ROOM"PVPP_KLM_VR"
CDS_LOCATION"FB7B1"
SEC"1"
SEC_TYPE"SM"
TOLERANCE"1%"
CDS_LIB"mstr_discrete";
"A"
$PN"1"7;
"B"
$PN"2"34;
%"CAP"
"1","(-5425,4150)","0","mstr_discrete","I207";
;
PACK_TYPE"0402"
PART_NUMBER"D97712-011"
MATERIAL"X6S"
LOCATION"C3M9"
VOLTAGE"16V"
TOLERANCE"10%"
VALUE"1.0UF"
ROOM"PVPP_KLM_VR"
CDS_LIB"mstr_discrete"
BOM_COST"PVPP_KLM_VR"
CDS_LOCATION"C3M9"
CDS_SEC"1"
$SEC"1"
REUSE_ID"1"
FIN"VR_1P2";
"A"
$PN"1"34;
"B"
$PN"2"6;
%"GND"
"1","(-3975,475)","0","mstr_symbols","I208";
;
BOM_COST"PVPP_KLM_VR"
ROOM"PVPP_KLM_VR"
SIZE"1B"
VOLTAGE"0"
CDS_LIB"mstr_symbols"
BODY_TYPE"PLUMBING"
HDL_POWER"GND";
"A\NAC"8;
%"CAP"
"1","(-3975,725)","0","mstr_discrete","I209";
;
LOCATION"C7B12"
PART_NUMBER"A36096-046"
PACK_TYPE"0402LF"
MATERIAL"X7R"
TOLERANCE"10%"
VOLTAGE"50V"
VALUE"1000PF"
ROOM"PVPP_KLM_VR"
BOM_COST"PVPP_KLM_VR"
CDS_LIB"mstr_discrete"
CDS_LOCATION"C7B12"
CDS_SEC"1"
$SEC"1"
REUSE_ID"17";
"A"
$PN"1"32;
"B"
$PN"2"8;
%"RES"
"2","(-4575,1250)","0","mstr_discrete","I210";
;
CDS_SEC"1"
PACK_TYPE"0402"
PART_NUMBER"G21796-026"
VALUE"1.00K"
MATERIAL"CHIP"
WATTAGE"1/16W"
LOCATION"R7B17"
TOLERANCE"1%"
REUSE_ID"21"
SEC_TYPE"0402"
BOM_COST"PVPP_KLM_VR"
SEC"1"
ROOM"PVPP_KLM_VR"
CDS_LOCATION"R7B17"
CDS_LIB"mstr_discrete";
"A"
$PN"1"9;
"B"
$PN"2"32;
%"P3V3_STBY"
"1","(-4575,1525)","0","mstr_symbols","I211";
;
VOLTAGE"+3.3V"
SIZE"1B"
CDS_LIB"mstr_symbols"
BODY_TYPE"PLUMBING"
HDL_POWER"P3V3_STBY";
"G\NAC"9;
%"NCP3232L"
"1","(-4150,2875)","0","mstr_vreg","I214";
;
CDS_SEC"1"
MATERIAL"IC"
LOCATION"EU7B1"
PART_NUMBER"H86355-001"
CDS_LOCATION"EU7B1"
SEC"1"
SEC_TYPE"SM"
PACK_TYPE"SM"
CDS_LMAN_SYM_OUTLINE"-450,850,450,-900"
CDS_LIB"mstr_vreg";
"PG"
$PN"7"32;
"PGND<0>"
$PN"16"10;
"PGND<1>"
$PN"17"10;
"PGND<2>"
$PN"18"10;
"PGND<3>"
$PN"19"10;
"PGND<4>"
$PN"20"10;
"PGND<5>"
$PN"21"10;
"PGND<6>"
$PN"22"10;
"PGND<8>"
$PN"24"10;
"PGND<7>"
$PN"23"10;
"PGND<9>"
$PN"25"10;
"PGND<10>"
$PN"26"10;
"PGND<11>"
$PN"27"10;
"PGND<12>"
$PN"28"10;
"PGND<13>"
$PN"37"10;
"GND"
$PN"41"10;
"AGND"
$PN"5"18;
"EN"
$PN"40"30;
"SS"
$PN"1"46;
"ISET"
$PN"4"33;
"OTS"
$PN"6"21;
"VIN<6>"
$PN"14"34;
"VIN<7>"
$PN"42"34;
"VCC"
$PN"39"34;
"VIN<1>"
$PN"9"34;
"VIN<5>"
$PN"13"34;
"VIN<4>"
$PN"12"34;
"VIN<3>"
$PN"11"34;
"VIN<2>"
$PN"10"34;
"VIN<0>"
$PN"8"34;
"VB"
$PN"38"35;
"COMP"
$PN"3"39;
"FB"
$PN"2"31;
"VSWH<1>"
$PN"29"40;
"VSWH<0>"
$PN"15"40;
"VSW"
$PN"35"40;
"VSWH<2>"
$PN"30"40;
"VSWH<3>"
$PN"31"40;
"VSWH<4>"
$PN"32"40;
"VSWH<5>"
$PN"33"40;
"VSWH<6>"
$PN"34"40;
"BST"
$PN"36"44;
"VSWH<7>"
$PN"43"40;
%"GND"
"1","(-3425,1925)","0","mstr_symbols","I215";
;
ROOM"PVPP_KLM_VR"
SIZE"1B"
VOLTAGE"0"
CDS_LIB"mstr_symbols"
BOM_COST"PVPP_KLM_VR"
BODY_TYPE"PLUMBING"
HDL_POWER"GND";
"A\NAC"10;
%"RES"
"2","(-2875,3325)","0","mstr_discrete","I218";
;
CDS_SEC"1"
TOLERANCE"5%"
LOCATION"R7A15"
VALUE"2.2"
MATERIAL"EMPTY"
PACK_TYPE"0402"
WATTAGE"1/16W"
PART_NUMBER"G21497-016"
SEC_TYPE"0402"
REUSE_ID"29"
SEC"1"
BOM_COST"PVPP_KLM_VR"
ROOM"PVPP_KLM_VR"
CDS_LOCATION"R7A15"
CDS_LIB"mstr_discrete";
"A"
$PN"1"36;
"B"
$PN"2"11;
%"GND"
"1","(-2875,3150)","0","mstr_symbols","I219";
;
BOM_COST"PVPP_KLM_VR"
ROOM"PVPP_KLM_VR"
CDS_LIB"mstr_symbols"
VOLTAGE"0"
SIZE"1B"
BODY_TYPE"PLUMBING"
HDL_POWER"GND";
"A\NAC"11;
%"CAP"
"1","(-2875,3700)","0","mstr_discrete","I220";
;
CDS_SEC"1"
TOLERANCE"10%"
LOCATION"C7A34"
VALUE"3300PF"
VOLTAGE"50V"
MATERIAL"EMPTY"
PACK_TYPE"0402LF"
PART_NUMBER"A36096-091"
SEC_TYPE"0402LF"
REUSE_ID"26"
BOM_COST"PVPP_KLM_VR"
SEC"1"
ROOM"PVPP_KLM_VR"
CDS_LOCATION"C7A34"
CDS_LIB"mstr_discrete";
"A"
$PN"1"40;
"B"
$PN"2"36;
%"GND"
"1","(-2400,3400)","0","mstr_symbols","I226";
;
BOM_COST"PVPP_KLM_VR"
ROOM"PVPP_KLM_VR"
SIZE"1B"
CDS_LIB"mstr_symbols"
VOLTAGE"0"
BODY_TYPE"PLUMBING"
HDL_POWER"GND";
"A\NAC"12;
%"RES"
"2","(-2400,3650)","0","mstr_discrete","I227";
;
CDS_SEC"1"
VALUE"120.0"
TOLERANCE"1%"
WATTAGE"1/10W"
MATERIAL"CHIP"
PART_NUMBER"G22026-003"
PACK_TYPE"0603"
LOCATION"R7B10"
BOM_COST"PVPP_KLM_VR"
REUSE_ID"34"
SEC"1"
SEC_TYPE"0603"
ROOM"PVPP_KLM_VR"
CDS_LIB"mstr_discrete"
CDS_LOCATION"R7B10";
"A"
$PN"1"5;
"B"
$PN"2"12;
%"GND"
"1","(-2100,3275)","0","mstr_symbols","I228";
;
HDL_POWER"GND"
BODY_TYPE"PLUMBING"
BOM_COST"PVPP_KLM_VR"
ROOM"PVPP_KLM_VR"
CDS_LIB"mstr_symbols"
VOLTAGE"0"
SIZE"1B";
"A\NAC"13;
%"CAPP"
"1","(-2100,3650)","0","mstr_discrete","I229";
;
TOLERANCE"20%"
GROUP"PWR_BULK_CAP"
PART_NUMBER"724613-042"
PACK_TYPE"7343LF"
MATERIAL"POSCAP"
VOLTAGE"6.3V"
VALUE"330UF"
LOCATION"C6B7"
BOM_COST"PVPP_KLM_VR"
ROOM"PVPP_KLM_VR"
CDS_LIB"mstr_discrete"
CDS_LOCATION"C6B7"
$SEC"1"
CDS_SEC"1"
REUSE_ID"28";
"B"
$PN"2"13;
"A"
$PN"1"5;
%"GND"
"1","(-1475,3425)","0","mstr_symbols","I235";
;
SIZE"1B"
VOLTAGE"0"
CDS_LIB"mstr_symbols"
ROOM"PVPP_KLM_VR"
BOM_COST"PVPP_KLM_VR"
BODY_TYPE"PLUMBING"
HDL_POWER"GND";
"A\NAC"14;
%"CAP"
"1","(-1475,3675)","0","mstr_discrete","I236";
;
TOLERANCE"20%"
MATERIAL"X6S"
LOCATION"C6B3"
VALUE"47UF"
VOLTAGE"4V"
GROUP"PWR_MLCC_CAP"
PART_NUMBER"C95333-006"
PACK_TYPE"0805"
REUSE_ID"33"
CDS_SEC"1"
$SEC"1"
CDS_LOCATION"C6B3"
CDS_LIB"mstr_discrete"
BOM_COST"PVPP_KLM_VR"
ROOM"PVPP_KLM_VR";
"A"
$PN"1"5;
"B"
$PN"2"14;
%"GND"
"1","(-1200,3400)","0","mstr_symbols","I237";
;
SIZE"1B"
VOLTAGE"0"
CDS_LIB"mstr_symbols"
ROOM"PVPP_KLM_VR"
BOM_COST"PVPP_KLM_VR"
BODY_TYPE"PLUMBING"
HDL_POWER"GND";
"A\NAC"15;
%"CAP"
"1","(-1200,3675)","0","mstr_discrete","I238";
;
LOCATION"C7B7"
TOLERANCE"20%"
VALUE"47UF"
VOLTAGE"4V"
MATERIAL"X6S"
GROUP"PWR_MLCC_CAP"
PACK_TYPE"0805"
PART_NUMBER"C95333-006"
REUSE_ID"33"
CDS_SEC"1"
$SEC"1"
BOM_COST"PVPP_KLM_VR"
CDS_LIB"mstr_discrete"
CDS_LOCATION"C7B7"
ROOM"PVPP_KLM_VR";
"A"
$PN"1"5;
"B"
$PN"2"15;
%"INDUCTOR"
"1","(-2550,3850)","0","mstr_discrete","I239";
;
LOCATION"L7B1"
VALUE"0.47UH"
PACK_TYPE"SM"
MATERIAL"IND"
PART_NUMBER"E13358-018"
CDS_LIB"mstr_discrete"
BOM_COST"PVPP_KLM_VR"
ROOM"PVPP_KLM_VR"
TOLERANCE"1%"
REUSE_ID"30"
CDS_SEC"1"
$SEC"1"
CDS_LOCATION"L7B1";
"INA\NAC"
$PN"1"40;
"INB\NAC"
$PN"2"5;
%"CAP"
"2","(-3675,4200)","2","mstr_discrete","I241";
;
CDS_LOCATION"C7B30"
LOCATION"C7B30"
PART_NUMBER"602433-020"
PACK_TYPE"0603LF"
VOLTAGE"25V"
VALUE"0.1UF"
TOLERANCE"10%"
MATERIAL"X7R"
CDS_LIB"mstr_discrete"
ROOM"PVPP_KLM_VR"
REUSE_ID"27"
SPOF"TRUE"
CDS_SEC"1"
$SEC"1"
BOM_COST"PVPP_KLM_VR";
"A"
$PN"1"40;
"B"
$PN"2"43;
%"AGND_SCSI"
"1","(-6125,2025)","0","mstr_symbols","I247";
;
HDL_POWER"AGND_PVPP_DEF"
CDS_LIB"mstr_symbols"
VOLTAGE"0.0V"
BOM_COST"PVPP_KLM_VR"
ROOM"PVPP_KLM_VR"
BODY_TYPE"PLUMBING";
"A"16;
%"AGND_SCSI"
"1","(-5425,1950)","0","mstr_symbols","I248";
;
HDL_POWER"AGND_PVPP_DEF"
BOM_COST"PVPP_KLM_VR"
VOLTAGE"0.0V"
CDS_LIB"mstr_symbols"
ROOM"PVPP_KLM_VR"
BODY_TYPE"PLUMBING";
"A"17;
%"AGND_SCSI"
"1","(-4725,1850)","0","mstr_symbols","I249";
;
HDL_POWER"AGND_PVPP_DEF"
CDS_LIB"mstr_symbols"
VOLTAGE"0.0V"
ROOM"PVPP_KLM_VR"
BOM_COST"PVPP_KLM_VR"
BODY_TYPE"PLUMBING";
"A"18;
%"AGND_SCSI"
"1","(-5100,1350)","0","mstr_symbols","I250";
;
HDL_POWER"AGND_PVPP_DEF"
VOLTAGE"0"
CDS_LIB"mstr_symbols"
BODY_TYPE"PLUMBING";
"A"19;
%"AGND_SCSI"
"1","(-6825,2125)","0","mstr_symbols","I251";
;
HDL_POWER"AGND_PVPP_DEF"
VOLTAGE"0.0V"
CDS_LIB"mstr_symbols"
BOM_COST"PVPP_KLM_VR"
ROOM"PVPP_KLM_VR"
BODY_TYPE"PLUMBING";
"A"20;
%"CAP_A"
"1","(-5475,3525)","0","dev_discrete","I252";
;
PACK_TYPE"0402V"
PART_NUMBER"A36096-030"
TOLERANCE"10%"
MATERIAL"X7R"
LOCATION"C7B6"
VALUE"0.1UF"
VOLTAGE"16V"
SEC"1"
SEC_TYPE"0402V"
CDS_SEC"1"
CDS_LOCATION"C7B6"
CDS_LIB"dev_discrete";
"B"
$PN"2"22;
"A"
$PN"1"34;
%"CAP"
"1","(-6125,2425)","0","mstr_discrete","I253";
;
CDS_SEC"1"
PART_NUMBER"E15431-003"
PACK_TYPE"0603"
MATERIAL"X6S"
TOLERANCE"10%"
VOLTAGE"6.3V"
LOCATION"C3M10"
CONFIG"078.47521.08BD"
VALUE"4.7UF"
REUSE_ID"26"
SEC_TYPE"0603"
BOM_COST"PVPP_KLM_VR"
SEC"1"
ROOM"PVPP_KLM_VR"
CDS_LIB"mstr_discrete"
CDS_LOCATION"C3M10";
"A"
$PN"1"35;
"B"
$PN"2"16;
%"AGND_SCSI"
"1","(-5775,2725)","0","mstr_symbols","I254";
;
HDL_POWER"AGND_PVPP_DEF"
CDS_LIB"mstr_symbols"
VOLTAGE"0.0V"
ROOM"PVPP_KLM_VR"
BOM_COST"PVPP_KLM_VR"
BODY_TYPE"PLUMBING";
"A"21;
%"GND"
"1","(-5475,3275)","0","mstr_symbols","I255";
;
VOLTAGE"0"
CDS_LIB"mstr_symbols"
SIZE"1B"
ROOM"PVPP_KLM_VR"
BOM_COST"PVPP_KLM_VR"
BODY_TYPE"PLUMBING"
HDL_POWER"GND";
"A\NAC"22;
%"RES"
"1","(-3650,975)","0","mstr_discrete","I257";
;
CDS_SEC"1"
PART_NUMBER"G21796-250"
VALUE"22.1"
LOCATION"R7B12"
TOLERANCE"1.0%"
PACK_TYPE"0402"
MATERIAL"CHIP"
WATTAGE"1/16W"
ROOM"PVPP_DEF_VR"
CDS_LOCATION"R7B12"
SEC"1"
SEC_TYPE"0402"
CDS_LIB"mstr_discrete";
"B"
$PN"2"38;
"A"
$PN"1"32;
%"CAP"
"1","(-6950,4100)","0","mstr_discrete","I259";
;
CDS_SEC"1"
VOLTAGE"16V"
TOLERANCE"10%"
MATERIAL"X6S"
PACK_TYPE"0805"
PART_NUMBER"C95333-007"
VALUE"10UF"
LOCATION"C3M8"
CDS_LIB"mstr_discrete"
CDS_LOCATION"C3M8"
SEC_TYPE"0805"
SEC"1";
"A"
$PN"1"34;
"B"
$PN"2"23;
%"CAP"
"1","(-6600,4100)","0","mstr_discrete","I260";
;
CDS_SEC"1"
TOLERANCE"10%"
LOCATION"C3M15"
VALUE"10UF"
VOLTAGE"16V"
PACK_TYPE"0805"
MATERIAL"X6S"
PART_NUMBER"C95333-007"
SEC"1"
SEC_TYPE"0805"
CDS_LOCATION"C3M15"
CDS_LIB"mstr_discrete";
"A"
$PN"1"34;
"B"
$PN"2"24;
%"CAP"
"1","(-6225,4100)","0","mstr_discrete","I261";
;
CDS_SEC"1"
MATERIAL"X6S"
PART_NUMBER"C95333-007"
VALUE"10UF"
VOLTAGE"16V"
TOLERANCE"10%"
PACK_TYPE"0805"
LOCATION"C3M16"
SEC"1"
SEC_TYPE"0805"
CDS_LOCATION"C3M16"
CDS_LIB"mstr_discrete";
"A"
$PN"1"34;
"B"
$PN"2"25;
%"CAP"
"1","(-5850,4100)","0","mstr_discrete","I262";
;
CDS_SEC"1"
PART_NUMBER"C95333-007"
LOCATION"C7B5"
VALUE"10UF"
VOLTAGE"16V"
TOLERANCE"10%"
PACK_TYPE"0805"
MATERIAL"X6S"
SEC"1"
SEC_TYPE"0805"
CDS_LOCATION"C7B5"
CDS_LIB"mstr_discrete";
"A"
$PN"1"34;
"B"
$PN"2"26;
%"GND"
"1","(-6950,3900)","0","mstr_symbols","I263";
;
BOM_COST"PVPP_KLM_VR"
ROOM"PVPP_KLM_VR"
VOLTAGE"0"
CDS_LIB"mstr_symbols"
SIZE"1B"
BODY_TYPE"PLUMBING"
HDL_POWER"GND";
"A\NAC"23;
%"GND"
"1","(-6600,3900)","0","mstr_symbols","I264";
;
SIZE"1B"
CDS_LIB"mstr_symbols"
VOLTAGE"0"
ROOM"PVPP_KLM_VR"
BOM_COST"PVPP_KLM_VR"
BODY_TYPE"PLUMBING"
HDL_POWER"GND";
"A\NAC"24;
%"GND"
"1","(-6225,3900)","0","mstr_symbols","I265";
;
SIZE"1B"
CDS_LIB"mstr_symbols"
VOLTAGE"0"
ROOM"PVPP_KLM_VR"
BOM_COST"PVPP_KLM_VR"
BODY_TYPE"PLUMBING"
HDL_POWER"GND";
"A\NAC"25;
%"GND"
"1","(-5850,3900)","0","mstr_symbols","I266";
;
SIZE"1B"
CDS_LIB"mstr_symbols"
VOLTAGE"0"
ROOM"PVPP_KLM_VR"
BOM_COST"PVPP_KLM_VR"
BODY_TYPE"PLUMBING"
HDL_POWER"GND";
"A\NAC"26;
%"CAPP"
"1","(-1800,3650)","0","mstr_discrete","I267";
;
CDS_SEC"1"
VOLTAGE"4V"
VALUE"220UF"
LOCATION"C4M1"
TOLERANCE"20%"
MATERIAL"POSCAP"
PACK_TYPE"7343"
PART_NUMBER"724613-067"
GROUP"PWR_BULK_CAP"
SEC_TYPE"7343"
SEC"1"
CDS_LOCATION"C4M1"
CDS_LIB"mstr_discrete";
"B"
$PN"2"13;
"A"
$PN"1"5;
%"RES"
"2","(-1350,2525)","0","mstr_discrete","I298";
;
CDS_SEC"1"
VALUE"1.0K"
LOCATION"R7B18"
TOLERANCE"0.1%"
WATTAGE"1/16W"
PACK_TYPE"0402"
MATERIAL"CHIP"
PART_NUMBER"G85996-004"
CDS_LIB"mstr_discrete"
CDS_LOCATION"R7B18"
BOM_COST"PVPP_KLM_VR"
ROOM"PVPP_KLM_VR"
SEC"1"
REUSE_ID"9"
SPOF"TRUE"
SEC_TYPE"0402";
"A"
$PN"1"41;
"B"
$PN"2"37;
%"RES"
"1","(-1700,2925)","5","mstr_discrete","I299";
;
CDS_SEC"1"
PART_NUMBER"G21497-005"
VALUE"0.0"
WATTAGE"1/16W"
TOLERANCE"5%"
PACK_TYPE"0402"
MATERIAL"CHIP"
LOCATION"R7B11"
SEC"1"
SPOF"TRUE"
SEC_TYPE"0402"
ROOM"PVPP_KLM_VR"
CDS_LOCATION"R7B11"
CDS_LIB"mstr_discrete";
"B"
$PN"2"41;
"A"
$PN"1"5;
%"RES"
"1","(-2400,2450)","0","mstr_discrete","I300";
;
CDS_SEC"1"
LOCATION"R7B16"
VALUE"7.87K"
PART_NUMBER"G21796-242"
PACK_TYPE"0402"
MATERIAL"CHIP"
TOLERANCE"1.0%"
WATTAGE"1/16W"
REUSE_ID"13"
SEC_TYPE"0402"
SEC"1"
ROOM"PVPP_KLM_VR"
CDS_LOCATION"R7B16"
CDS_LIB"mstr_discrete"
BOM_COST"PVPP_KLM_VR";
"B"
$PN"2"31;
"A"
$PN"1"42;
%"CAP"
"2","(-2600,2825)","2","mstr_discrete","I301";
;
CDS_SEC"1"
TOLERANCE"5%"
PACK_TYPE"0402LF"
PART_NUMBER"A36095-026"
VOLTAGE"50V"
VALUE"100.0PF"
MATERIAL"COG"
LOCATION"C7B10"
REUSE_ID"27"
SEC_TYPE"0402LF"
SEC"1"
ROOM"PVPP_KLM_VR"
CDS_LOCATION"C7B10"
CDS_LIB"mstr_discrete"
BOM_COST"PVPP_KLM_VR";
"A"
$PN"1"31;
"B"
$PN"2"39;
%"CAP"
"1","(-1350,1775)","0","mstr_discrete","I302";
;
CDS_SEC"1"
PART_NUMBER"A36096-075"
PACK_TYPE"0402LF"
TOLERANCE"10%"
LOCATION"C7B13"
MATERIAL"X7R"
VOLTAGE"50V"
VALUE"2200PF"
SEC"1"
CDS_LIB"mstr_discrete"
BOM_COST"PVPP_KLM_VR"
CDS_LOCATION"C7B13"
ROOM"PVPP_KLM_VR"
REUSE_ID"26"
SEC_TYPE"0402LF"
SPOF"TRUE";
"A"
$PN"1"37;
"B"
$PN"2"31;
%"RES"
"2","(-1700,1850)","0","mstr_discrete","I303";
;
PART_NUMBER"G21796-040"
MATERIAL"CHIP"
PACK_TYPE"0402"
WATTAGE"1/16W"
TOLERANCE"1%"
VALUE"20.0K"
LOCATION"R7B15"
CDS_LIB"mstr_discrete"
CDS_LOCATION"R7B15"
SPOF"TRUE"
CDS_SEC"1"
ROOM"PVPP_KLM_VR"
REUSE_ID"9"
BOM_COST"PVPP_KLM_VR"
$SEC"1";
"A"
$PN"1"41;
"B"
$PN"2"31;
%"CAP"
"2","(-3200,2450)","2","mstr_discrete","I306";
;
CDS_SEC"1"
LOCATION"C7B14"
MATERIAL"X7R"
VOLTAGE"50V"
VALUE"2200PF"
TOLERANCE"10%"
PACK_TYPE"0402LF"
PART_NUMBER"A36096-075"
ROOM"PVPP_KLM_VR"
SEC"1"
REUSE_ID"27"
BOM_COST"PVPP_KLM_VR"
SEC_TYPE"0402LF"
CDS_LOCATION"C7B14"
CDS_LIB"mstr_discrete";
"A"
$PN"1"42;
"B"
$PN"2"39;
%"RES"
"1","(-6500,2825)","0","mstr_discrete","I307";
;
CDS_SEC"1"
LOCATION"R7B9"
MATERIAL"CHIP"
PACK_TYPE"0402"
TOLERANCE"5%"
PART_NUMBER"G21497-005"
WATTAGE"1/16W"
VALUE"0.0"
ROOM"PVCCIN_CPU0_VR"
CDS_LOCATION"R7B9"
SEC"1"
CDS_LIB"mstr_discrete"
SEC_TYPE"0402";
"B"
$PN"2"30;
"A"
$PN"1"45;
%"AGND_SCSI"
"1","(-1700,950)","0","mstr_symbols","I308";
;
HDL_POWER"AGND_PVPP_DEF"
BODY_TYPE"PLUMBING"
BOM_COST"PVPP_KLM_VR"
ROOM"PVPP_KLM_VR"
VOLTAGE"0.0V"
CDS_LIB"mstr_symbols";
"A"27;
%"SC22U16V5MX-4-GP"
"1","(-7600,4100)","0","w_hdl","I309";
;
CDS_SEC"1"
CDS_LOCATION"C7B8"
TOLERANCE"20%"
RATED"16V"
TYPE"X6S"
PACK_SIZE"0805"
ATTRIBUTE"22UF"
LOCATION"C7B8"
VALUE"SC22U16V5MX-4-GP"
CDS_LMAN_SYM_OUTLINE"-50,25,50,-25"
CDS_LIB"w_hdl"
PART_NUMBER"078.22611.0811"
SEC_TYPE"SMD-BCG5"
SEC"1"
PACK_TYPE"SMD-BCG5";
"2"
$PN"2"29;
"1"
$PN"1"34;
%"GND"
"1","(-7300,3850)","0","mstr_symbols","I310";
;
SIZE"1B"
VOLTAGE"0"
ROOM"PVPP_KLM_VR"
BOM_COST"PVPP_KLM_VR"
CDS_LIB"mstr_symbols"
BODY_TYPE"PLUMBING"
HDL_POWER"GND";
"A\NAC"28;
%"SC22U16V5MX-4-GP"
"1","(-7300,4100)","0","w_hdl","I311";
;
CDS_SEC"1"
CDS_LOCATION"C22W7"
LOCATION"C22W7"
TOLERANCE"20%"
RATED"16V"
TYPE"X6S"
PACK_SIZE"0805"
VALUE"SC22U16V5MX-4-GP"
ATTRIBUTE"22UF"
CDS_LMAN_SYM_OUTLINE"-50,25,50,-25"
CDS_LIB"w_hdl"
PART_NUMBER"078.22611.0811"
SEC_TYPE"SMD-BCG5"
SEC"1"
PACK_TYPE"SMD-BCG5";
"2"
$PN"2"28;
"1"
$PN"1"34;
%"GND"
"1","(-7600,3850)","0","mstr_symbols","I312";
;
SIZE"1B"
VOLTAGE"0"
ROOM"PVPP_KLM_VR"
BOM_COST"PVPP_KLM_VR"
CDS_LIB"mstr_symbols"
BODY_TYPE"PLUMBING"
HDL_POWER"GND";
"A\NAC"29;
%"RES"
"1","(-4500,4175)","0","mstr_discrete","I313";
;
WATTAGE"1/10W"
PACK_TYPE"0603"
VALUE"0"
TOLERANCE"5.0%"
LOCATION"R7B19"
PART_NUMBER"G22178-002"
MATERIAL"CHIP"
CDS_LOCATION"R7B19"
ROOM"NIC_SPRV"
BOM_COST"NT_GBE_BASE"
CDS_LIB"mstr_discrete"
SEC_TYPE"0603"
SEC"1"
CDS_SEC"1";
"B"
$PN"2"43;
"A"
$PN"1"44;
%"RES"
"2","(-1700,1300)","0","mstr_discrete","I314";
;
TOLERANCE"1%"
WATTAGE"1/16W"
MATERIAL"CHIP"
PART_NUMBER"G21796-161"
LOCATION"R7B13"
PACK_TYPE"0402"
VALUE"6.19K"
CDS_SEC"1"
CDS_LIB"mstr_discrete"
ROOM"IO_SLOT"
SEC_TYPE"0402"
SEC"1"
BOM_COST"IO_SLOT"
CDS_LOCATION"R7B13";
"A"
$PN"1"31;
"B"
$PN"2"27;
%"RES"
"2","(-5100,1650)","2","mstr_discrete","I315";
;
TOLERANCE"1.0%"
PACK_TYPE"0402"
LOCATION"R7B14"
MATERIAL"CHIP"
WATTAGE"1/16W"
NEW_VALUE"3.9K"
CONFIG"64.39015.6DL"
CDS_SEC"1"
$SEC"1"
CDS_LIB"mstr_discrete"
BOM_COST"PVPP_KLM_VR"
ROOM"PVPP_KLM_VR"
VALUE"7.87K"
PART_NUMBER"G21796-242"
CDS_LOCATION"R7B14";
"A"
$PN"1"33;
"B"
$PN"2"19;
END.
